FILE_TYPE = MACRO_DRAWING;
SET COLOR_WIRE YELLOW;
SET COLOR_PROP ORANGE;
SET COLOR_DOT WHITE;
SET COLOR_ARC YELLOW;
SET COLOR_BODY GREEN;
SET COLOR_NOTE PURPLE;
SET PROP_DISPLAY VALUE;
SET PAGE_NUMBER P192;
FORCEADD Q_RES..1
(1150 3150);
FORCEPROP 1 LAST PART_NUMBER CS21002FB06
J 0
(1000 3250);
DISPLAY 0.787234 (1000 3250);
DISPLAY INVISIBLE (1000 3250);
FORCEPROP 1 LAST VALUE 1K
J 2
(1375 3150);
DISPLAY 0.638298 (1375 3150);
FORCEPROP 1 LAST WATTAGE 1/16W
J 2
(1575 3325);
DISPLAY 0.787234 (1575 3325);
FORCEPROP 1 LAST MATERIAL CHIP
J 0
(1500 3150);
DISPLAY 0.638298 (1500 3150);
FORCEPROP 1 LAST TOLERANCE 1%
J 0
(1400 3150);
DISPLAY 0.638298 (1400 3150);
FORCEPROP 1 LAST PACK_TYPE 0402LF
J 0
(1000 3325);
DISPLAY 0.787234 (1000 3325);
FORCEPROP 1 LAST $LOCATION R3040
J 0
(900 3150);
DISPLAY 0.787234 (900 3150);
FORCEPROP 1 LASTPIN (1050 3150) $PN 1
J 0
(1062 3162);
DISPLAY 0.787234 (1062 3162);
FORCEPROP 1 LASTPIN (1250 3150) $PN 2
J 0
(1212 3162);
DISPLAY 0.787234 (1212 3162);
FORCEPROP 1 LAST PATH I1
J 0
(1100 3300);
DISPLAY 0.978723 (1100 3300);
PAINT WHITE (1100 3300);
DISPLAY INVISIBLE (1100 3300);
FORCEPROP 2 LAST CDS_LIB pure_quanta
J 0
(1150 3150);
PAINT MONO (1150 3150);
DISPLAY INVISIBLE (1150 3150);
FORCEPROP 2 LAST CDS_LOCATION R3040
J 0
(1575 3375);
DISPLAY 1.021277 (1575 3375);
DISPLAY INVISIBLE (1575 3375);
FORCEPROP 2 LAST $SEC 1
J 0
(1575 3375);
DISPLAY 0.680851 (1575 3375);
PAINT MONO (1575 3375);
DISPLAY INVISIBLE (1575 3375);
FORCEPROP 2 LAST CDS_SEC 1
J 0
(1575 3375);
DISPLAY 1.021277 (1575 3375);
DISPLAY INVISIBLE (1575 3375);
FORCEADD Q_RES..1
(1200 1050);
FORCEPROP 1 LAST PART_NUMBER CS31002FB08
J 0
(1050 1150);
DISPLAY 0.787234 (1050 1150);
DISPLAY INVISIBLE (1050 1150);
FORCEPROP 1 LAST MATERIAL EMPTY
J 0
(1575 1050);
DISPLAY 0.787234 (1575 1050);
PAINT RED (1575 1050);
FORCEPROP 1 LAST VALUE 10K
J 2
(1450 1050);
DISPLAY 0.787234 (1450 1050);
FORCEPROP 1 LAST TOLERANCE 1%
J 0
(1475 1050);
DISPLAY 0.787234 (1475 1050);
FORCEPROP 1 LAST $LOCATION R1262
J 0
(950 1050);
DISPLAY 0.787234 (950 1050);
FORCEPROP 1 LASTPIN (1100 1050) $PN 1
J 0
(1112 1062);
DISPLAY 0.787234 (1112 1062);
FORCEPROP 1 LASTPIN (1300 1050) $PN 2
J 0
(1262 1062);
DISPLAY 0.787234 (1262 1062);
FORCEPROP 1 LAST PATH I11
J 0
(1150 1200);
DISPLAY 0.978723 (1150 1200);
PAINT WHITE (1150 1200);
DISPLAY INVISIBLE (1150 1200);
FORCEPROP 2 LAST CDS_LIB pure_quanta
J 0
(1200 1050);
PAINT MONO (1200 1050);
DISPLAY INVISIBLE (1200 1050);
FORCEPROP 1 LAST PACK_TYPE 0402LF
J 0
(1050 1225);
DISPLAY 0.787234 (1050 1225);
DISPLAY INVISIBLE (1050 1225);
FORCEPROP 1 LAST WATTAGE 1/16W
J 2
(1625 1225);
DISPLAY 0.787234 (1625 1225);
DISPLAY INVISIBLE (1625 1225);
FORCEPROP 2 LAST CDS_LOCATION R1262
J 0
(1150 1250);
DISPLAY 1.021277 (1150 1250);
DISPLAY INVISIBLE (1150 1250);
FORCEPROP 2 LAST $SEC 1
J 0
(1150 1250);
DISPLAY 0.680851 (1150 1250);
PAINT MONO (1150 1250);
DISPLAY INVISIBLE (1150 1250);
FORCEPROP 2 LAST CDS_SEC 1
J 0
(1150 1250);
DISPLAY 1.021277 (1150 1250);
DISPLAY INVISIBLE (1150 1250);
FORCEADD UNIVERSAL_POWER..1
(825 1600);
FORCEPROP 3 LASTPIN (825 1550) SIG_NAME P1V05_PCH_AUX\g
J 0
(835 1560);
DISPLAY 0.659574 (835 1560);
PAINT MONO (835 1560);
DISPLAY INVISIBLE (835 1560);
FORCEPROP 1 LAST HDL_POWER P1V05_PCH_AUX
J 1
(825 1650);
DISPLAY 0.872340 (825 1650);
PAINT GREEN (825 1650);
FORCEPROP 2 LAST CDS_LIB logical_power
J 0
(825 1600);
DISPLAY INVISIBLE (825 1600);
FORCEPROP 1 LAST PATH I12
J 0
(875 1625);
DISPLAY 0.872340 (875 1625);
PAINT AQUA (875 1625);
DISPLAY INVISIBLE (875 1625);
FORCEADD OFFPAGE..2
(2475 1175);
FORCEPROP 2 LAST $XR1 182 
J 0
(2784 1175);
DISPLAY 0.638298 (2784 1175);
PAINT MONO (2784 1175);
FORCEPROP 2 LAST $XR0 225 
J 0
(2664 1175);
DISPLAY 0.638298 (2664 1175);
PAINT MONO (2664 1175);
FORCEPROP 2 LAST PATH I13
J 0
(2675 1225);
DISPLAY 1.021277 (2675 1225);
DISPLAY INVISIBLE (2675 1225);
FORCEPROP 2 LAST CDS_LIB standard
J 0
(2475 1175);
DISPLAY INVISIBLE (2475 1175);
FORCEPROP 1 LAST OFFPAGE TRUE
J 0
(2800 1050);
DISPLAY 0.872340 (2800 1050);
PAINT GREEN (2800 1050);
DISPLAY INVISIBLE (2800 1050);
FORCEPROP 1 LAST COMMENT_BODY TRUE
J 0
(2430 1080);
DISPLAY 0.872340 (2430 1080);
PAINT GREEN (2430 1080);
DISPLAY INVISIBLE (2430 1080);
FORCEADD OFFPAGE..2
(2475 1300);
FORCEPROP 2 LAST $XR1 182 
J 0
(2784 1300);
DISPLAY 0.638298 (2784 1300);
PAINT MONO (2784 1300);
FORCEPROP 2 LAST $XR0 225 
J 0
(2664 1300);
DISPLAY 0.638298 (2664 1300);
PAINT MONO (2664 1300);
FORCEPROP 2 LAST CDS_LIB standard
J 0
(2475 1300);
DISPLAY INVISIBLE (2475 1300);
FORCEPROP 1 LAST OFFPAGE TRUE
J 0
(2800 1175);
DISPLAY 0.872340 (2800 1175);
PAINT GREEN (2800 1175);
DISPLAY INVISIBLE (2800 1175);
FORCEPROP 1 LAST COMMENT_BODY TRUE
J 0
(2430 1205);
DISPLAY 0.872340 (2430 1205);
PAINT GREEN (2430 1205);
DISPLAY INVISIBLE (2430 1205);
FORCEPROP 2 LAST PATH I14
J 0
(2675 1350);
DISPLAY 1.021277 (2675 1350);
DISPLAY INVISIBLE (2675 1350);
FORCEADD OFFPAGE..2
(2475 1050);
FORCEPROP 2 LAST $XR1 182 
J 0
(2784 1050);
DISPLAY 0.638298 (2784 1050);
PAINT MONO (2784 1050);
FORCEPROP 2 LAST $XR0 225 
J 0
(2664 1050);
DISPLAY 0.638298 (2664 1050);
PAINT MONO (2664 1050);
FORCEPROP 2 LAST PATH I16
J 0
(2675 1100);
DISPLAY 1.021277 (2675 1100);
DISPLAY INVISIBLE (2675 1100);
FORCEPROP 1 LAST COMMENT_BODY TRUE
J 0
(2430 955);
DISPLAY 0.872340 (2430 955);
PAINT GREEN (2430 955);
DISPLAY INVISIBLE (2430 955);
FORCEPROP 1 LAST OFFPAGE TRUE
J 0
(2800 925);
DISPLAY 0.872340 (2800 925);
PAINT GREEN (2800 925);
DISPLAY INVISIBLE (2800 925);
FORCEPROP 2 LAST CDS_LIB standard
J 0
(2475 1050);
DISPLAY INVISIBLE (2475 1050);
FORCEADD Q_RES..1
(1200 1300);
FORCEPROP 1 LAST PART_NUMBER CS31002FB08
J 0
(1050 1400);
DISPLAY 0.787234 (1050 1400);
DISPLAY INVISIBLE (1050 1400);
FORCEPROP 1 LAST TOLERANCE 1%
J 0
(1475 1300);
DISPLAY 0.787234 (1475 1300);
FORCEPROP 1 LAST MATERIAL EMPTY
J 0
(1575 1300);
DISPLAY 0.787234 (1575 1300);
PAINT RED (1575 1300);
FORCEPROP 1 LAST VALUE 10K
J 2
(1450 1300);
DISPLAY 0.787234 (1450 1300);
FORCEPROP 1 LAST WATTAGE 1/16W
J 2
(1625 1475);
DISPLAY 0.787234 (1625 1475);
FORCEPROP 1 LAST PACK_TYPE 0402LF
J 0
(1050 1475);
DISPLAY 0.787234 (1050 1475);
FORCEPROP 1 LAST $LOCATION R1260
J 0
(950 1300);
DISPLAY 0.787234 (950 1300);
FORCEPROP 1 LASTPIN (1100 1300) $PN 1
J 0
(1112 1312);
DISPLAY 0.787234 (1112 1312);
FORCEPROP 1 LASTPIN (1300 1300) $PN 2
J 0
(1262 1312);
DISPLAY 0.787234 (1262 1312);
FORCEPROP 2 LAST CDS_LIB pure_quanta
J 0
(1200 1300);
PAINT MONO (1200 1300);
DISPLAY INVISIBLE (1200 1300);
FORCEPROP 1 LAST PATH I17
J 0
(1150 1450);
DISPLAY 0.978723 (1150 1450);
PAINT WHITE (1150 1450);
DISPLAY INVISIBLE (1150 1450);
FORCEPROP 2 LAST CDS_LOCATION R1260
J 0
(1625 1525);
DISPLAY 1.021277 (1625 1525);
DISPLAY INVISIBLE (1625 1525);
FORCEPROP 2 LAST $SEC 1
J 0
(1625 1525);
DISPLAY 0.680851 (1625 1525);
PAINT MONO (1625 1525);
DISPLAY INVISIBLE (1625 1525);
FORCEPROP 2 LAST CDS_SEC 1
J 0
(1625 1525);
DISPLAY 1.021277 (1625 1525);
DISPLAY INVISIBLE (1625 1525);
FORCEADD Q_RES..1
(1200 1175);
FORCEPROP 1 LAST PART_NUMBER CS31002FB08
J 0
(1050 1275);
DISPLAY 0.787234 (1050 1275);
DISPLAY INVISIBLE (1050 1275);
FORCEPROP 1 LAST TOLERANCE 1%
J 0
(1475 1175);
DISPLAY 0.787234 (1475 1175);
FORCEPROP 1 LAST MATERIAL EMPTY
J 0
(1575 1175);
DISPLAY 0.787234 (1575 1175);
PAINT RED (1575 1175);
FORCEPROP 1 LAST VALUE 10K
J 2
(1450 1175);
DISPLAY 0.787234 (1450 1175);
FORCEPROP 1 LAST $LOCATION R3042
J 0
(950 1175);
DISPLAY 0.787234 (950 1175);
FORCEPROP 1 LASTPIN (1100 1175) $PN 1
J 0
(1112 1187);
DISPLAY 0.787234 (1112 1187);
FORCEPROP 1 LASTPIN (1300 1175) $PN 2
J 0
(1262 1187);
DISPLAY 0.787234 (1262 1187);
FORCEPROP 1 LAST PATH I18
J 0
(1150 1325);
DISPLAY 0.978723 (1150 1325);
PAINT WHITE (1150 1325);
DISPLAY INVISIBLE (1150 1325);
FORCEPROP 1 LAST WATTAGE 1/16W
J 2
(1625 1350);
DISPLAY 0.787234 (1625 1350);
DISPLAY INVISIBLE (1625 1350);
FORCEPROP 1 LAST PACK_TYPE 0402LF
J 0
(1050 1350);
DISPLAY 0.787234 (1050 1350);
DISPLAY INVISIBLE (1050 1350);
FORCEPROP 2 LAST CDS_LIB pure_quanta
J 0
(1200 1175);
PAINT MONO (1200 1175);
DISPLAY INVISIBLE (1200 1175);
FORCEPROP 2 LAST CDS_LOCATION R3042
J 0
(1150 1375);
DISPLAY 1.021277 (1150 1375);
DISPLAY INVISIBLE (1150 1375);
FORCEPROP 2 LAST $SEC 1
J 0
(1150 1375);
DISPLAY 0.680851 (1150 1375);
PAINT MONO (1150 1375);
DISPLAY INVISIBLE (1150 1375);
FORCEPROP 2 LAST CDS_SEC 1
J 0
(1150 1375);
DISPLAY 1.021277 (1150 1375);
DISPLAY INVISIBLE (1150 1375);
FORCEADD UNIVERSAL_POWER..1
(800 3375);
FORCEPROP 3 LASTPIN (800 3325) SIG_NAME P3V3_AUX\g
J 0
(810 3335);
DISPLAY 0.659574 (810 3335);
PAINT MONO (810 3335);
DISPLAY INVISIBLE (810 3335);
FORCEPROP 1 LAST HDL_POWER P3V3_AUX
J 1
(800 3425);
DISPLAY 0.872340 (800 3425);
PAINT GREEN (800 3425);
FORCEPROP 2 LAST CDS_LIB logical_power
J 0
(800 3375);
DISPLAY INVISIBLE (800 3375);
FORCEPROP 1 LAST PATH I2
J 0
(850 3400);
DISPLAY 0.872340 (850 3400);
PAINT AQUA (850 3400);
DISPLAY INVISIBLE (850 3400);
FORCEADD Q_RES..1
(-4950 3125);
FORCEPROP 1 LAST PART_NUMBER CS21002FB06
J 0
(-5100 3225);
DISPLAY 0.787234 (-5100 3225);
DISPLAY INVISIBLE (-5100 3225);
FORCEPROP 1 LAST VALUE 1K
J 2
(-4750 3125);
DISPLAY 0.638298 (-4750 3125);
FORCEPROP 1 LAST TOLERANCE 1%
J 0
(-4725 3125);
DISPLAY 0.638298 (-4725 3125);
FORCEPROP 1 LAST MATERIAL CHIP
J 0
(-4625 3125);
DISPLAY 0.638298 (-4625 3125);
FORCEPROP 1 LAST PACK_TYPE 0402LF
J 0
(-5100 3300);
DISPLAY 0.787234 (-5100 3300);
FORCEPROP 1 LAST WATTAGE 1/16W
J 2
(-4525 3300);
DISPLAY 0.787234 (-4525 3300);
FORCEPROP 1 LAST $LOCATION R1253
J 0
(-5200 3125);
DISPLAY 0.787234 (-5200 3125);
FORCEPROP 1 LASTPIN (-5050 3125) $PN 1
J 0
(-5038 3137);
DISPLAY 0.787234 (-5038 3137);
FORCEPROP 1 LASTPIN (-4850 3125) $PN 2
J 0
(-4888 3137);
DISPLAY 0.787234 (-4888 3137);
FORCEPROP 1 LAST PATH I23
J 0
(-5000 3275);
DISPLAY 0.978723 (-5000 3275);
PAINT WHITE (-5000 3275);
DISPLAY INVISIBLE (-5000 3275);
FORCEPROP 2 LAST CDS_LIB pure_quanta
J 0
(-4950 3125);
PAINT MONO (-4950 3125);
DISPLAY INVISIBLE (-4950 3125);
FORCEPROP 2 LAST CDS_LOCATION R1253
J 0
(-4525 3350);
DISPLAY 1.021277 (-4525 3350);
DISPLAY INVISIBLE (-4525 3350);
FORCEPROP 2 LAST $SEC 1
J 0
(-4525 3350);
DISPLAY 0.680851 (-4525 3350);
PAINT MONO (-4525 3350);
DISPLAY INVISIBLE (-4525 3350);
FORCEPROP 2 LAST CDS_SEC 1
J 0
(-4525 3350);
DISPLAY 1.021277 (-4525 3350);
DISPLAY INVISIBLE (-4525 3350);
FORCEADD Q_RES..1
(-4950 3000);
FORCEPROP 1 LAST PART_NUMBER CS31002FB08
J 0
(-5100 3100);
DISPLAY 0.787234 (-5100 3100);
DISPLAY INVISIBLE (-5100 3100);
FORCEPROP 1 LAST VALUE 10K
J 2
(-4750 3000);
DISPLAY 0.638298 (-4750 3000);
FORCEPROP 1 LAST MATERIAL CHIP
J 0
(-4625 3000);
DISPLAY 0.638298 (-4625 3000);
FORCEPROP 1 LAST TOLERANCE 1%
J 0
(-4725 3000);
DISPLAY 0.638298 (-4725 3000);
FORCEPROP 1 LAST $LOCATION R1254
J 0
(-5200 3000);
DISPLAY 0.787234 (-5200 3000);
FORCEPROP 1 LASTPIN (-5050 3000) $PN 1
J 0
(-5038 3012);
DISPLAY 0.787234 (-5038 3012);
FORCEPROP 1 LASTPIN (-4850 3000) $PN 2
J 0
(-4888 3012);
DISPLAY 0.787234 (-4888 3012);
FORCEPROP 2 LAST CDS_LIB pure_quanta
J 0
(-4950 3000);
PAINT MONO (-4950 3000);
DISPLAY INVISIBLE (-4950 3000);
FORCEPROP 1 LAST PACK_TYPE 0402LF
J 0
(-5100 3175);
DISPLAY 0.787234 (-5100 3175);
DISPLAY INVISIBLE (-5100 3175);
FORCEPROP 1 LAST WATTAGE 1/16W
J 2
(-4525 3175);
DISPLAY 0.787234 (-4525 3175);
DISPLAY INVISIBLE (-4525 3175);
FORCEPROP 1 LAST PATH I24
J 0
(-5000 3150);
DISPLAY 0.978723 (-5000 3150);
PAINT WHITE (-5000 3150);
DISPLAY INVISIBLE (-5000 3150);
FORCEPROP 2 LAST CDS_LOCATION R1254
J 0
(-5000 3200);
DISPLAY 1.021277 (-5000 3200);
DISPLAY INVISIBLE (-5000 3200);
FORCEPROP 2 LAST $SEC 1
J 0
(-5000 3200);
DISPLAY 0.680851 (-5000 3200);
PAINT MONO (-5000 3200);
DISPLAY INVISIBLE (-5000 3200);
FORCEPROP 2 LAST CDS_SEC 1
J 0
(-5000 3200);
DISPLAY 1.021277 (-5000 3200);
DISPLAY INVISIBLE (-5000 3200);
FORCEADD UNIVERSAL_POWER..1
(-5300 3425);
FORCEPROP 3 LASTPIN (-5300 3375) SIG_NAME PGPPA_AUX\g
J 0
(-5290 3385);
DISPLAY 0.659574 (-5290 3385);
PAINT MONO (-5290 3385);
DISPLAY INVISIBLE (-5290 3385);
FORCEPROP 1 LAST HDL_POWER PGPPA_AUX
J 1
(-5300 3475);
DISPLAY 0.872340 (-5300 3475);
PAINT GREEN (-5300 3475);
FORCEPROP 2 LAST CDS_LIB logical_power
J 0
(-5300 3425);
DISPLAY INVISIBLE (-5300 3425);
FORCEPROP 1 LAST PATH I25
J 0
(-5250 3450);
DISPLAY 0.872340 (-5250 3450);
PAINT AQUA (-5250 3450);
DISPLAY INVISIBLE (-5250 3450);
FORCEADD Q_RES..1
(-4950 2875);
FORCEPROP 1 LAST PART_NUMBER CS21002FB06
J 0
(-5100 2800);
DISPLAY 0.808511 (-5100 2800);
DISPLAY INVISIBLE (-5100 2800);
FORCEPROP 1 LAST VALUE 1K
J 2
(-4750 2875);
DISPLAY 0.787234 (-4750 2875);
FORCEPROP 1 LAST TOLERANCE 1%
J 0
(-4725 2875);
DISPLAY 0.787234 (-4725 2875);
FORCEPROP 1 LAST MATERIAL CHIP
J 0
(-4625 2875);
DISPLAY 0.787234 (-4625 2875);
FORCEPROP 1 LAST WATTAGE 1/16W
J 2
(-4525 2725);
DISPLAY 0.787234 (-4525 2725);
FORCEPROP 1 LAST PACK_TYPE 0402LF
J 0
(-5100 2725);
DISPLAY 0.787234 (-5100 2725);
FORCEPROP 1 LAST $LOCATION R1255
J 0
(-5200 2875);
DISPLAY 0.787234 (-5200 2875);
FORCEPROP 2 LAST CDS_LIB pure_quanta
J 0
(-4950 2875);
PAINT MONO (-4950 2875);
DISPLAY INVISIBLE (-4950 2875);
FORCEPROP 1 LAST PATH I26
J 0
(-5000 3025);
DISPLAY 0.978723 (-5000 3025);
PAINT WHITE (-5000 3025);
DISPLAY INVISIBLE (-5000 3025);
FORCEPROP 2 LAST CDS_LOCATION R1255
J 0
(-5000 3075);
DISPLAY 1.021277 (-5000 3075);
DISPLAY INVISIBLE (-5000 3075);
FORCEPROP 2 LAST $SEC 1
J 0
(-5000 3075);
DISPLAY 0.680851 (-5000 3075);
PAINT MONO (-5000 3075);
DISPLAY INVISIBLE (-5000 3075);
FORCEPROP 2 LAST CDS_SEC 1
J 0
(-5000 3075);
DISPLAY 1.021277 (-5000 3075);
DISPLAY INVISIBLE (-5000 3075);
FORCEPROP 1 LASTPIN (-5050 2875) $PN 1
J 0
(-5038 2887);
DISPLAY 0.787234 (-5038 2887);
DISPLAY INVISIBLE (-5038 2887);
FORCEPROP 1 LASTPIN (-4850 2875) $PN 2
J 0
(-4888 2887);
DISPLAY 0.787234 (-4888 2887);
DISPLAY INVISIBLE (-4888 2887);
FORCEADD OFFPAGE..2
(-3500 2875);
FORCEPROP 2 LAST $XR0 183 
J 0
(-3311 2875);
DISPLAY 0.638298 (-3311 2875);
PAINT MONO (-3311 2875);
FORCEPROP 2 LAST CDS_LIB standard
J 0
(-3500 2875);
DISPLAY INVISIBLE (-3500 2875);
FORCEPROP 1 LAST OFFPAGE TRUE
J 0
(-3175 2750);
DISPLAY 0.872340 (-3175 2750);
PAINT GREEN (-3175 2750);
DISPLAY INVISIBLE (-3175 2750);
FORCEPROP 1 LAST COMMENT_BODY TRUE
J 0
(-3545 2780);
DISPLAY 0.872340 (-3545 2780);
PAINT GREEN (-3545 2780);
DISPLAY INVISIBLE (-3545 2780);
FORCEPROP 2 LAST PATH I28
J 0
(-3300 2925);
DISPLAY 1.021277 (-3300 2925);
DISPLAY INVISIBLE (-3300 2925);
FORCEADD OFFPAGE..2
(-3500 3125);
FORCEPROP 2 LAST $XR1 183 
J 0
(-3191 3125);
DISPLAY 0.638298 (-3191 3125);
PAINT MONO (-3191 3125);
FORCEPROP 2 LAST $XR0 202 
J 0
(-3311 3125);
DISPLAY 0.638298 (-3311 3125);
PAINT MONO (-3311 3125);
FORCEPROP 2 LAST CDS_LIB standard
J 0
(-3500 3125);
DISPLAY INVISIBLE (-3500 3125);
FORCEPROP 1 LAST OFFPAGE TRUE
J 0
(-3175 3000);
DISPLAY 0.872340 (-3175 3000);
PAINT GREEN (-3175 3000);
DISPLAY INVISIBLE (-3175 3000);
FORCEPROP 1 LAST COMMENT_BODY TRUE
J 0
(-3545 3030);
DISPLAY 0.872340 (-3545 3030);
PAINT GREEN (-3545 3030);
DISPLAY INVISIBLE (-3545 3030);
FORCEPROP 2 LAST PATH I29
J 0
(-3300 3175);
DISPLAY 1.021277 (-3300 3175);
DISPLAY INVISIBLE (-3300 3175);
FORCEADD OFFPAGE..2
(2475 3150);
FORCEPROP 2 LAST $XR1 183 
J 0
(2784 3150);
DISPLAY 0.638298 (2784 3150);
PAINT MONO (2784 3150);
FORCEPROP 2 LAST $XR0 215 
J 0
(2664 3150);
DISPLAY 0.638298 (2664 3150);
PAINT MONO (2664 3150);
FORCEPROP 2 LAST PATH I3
J 0
(2675 3200);
DISPLAY 1.021277 (2675 3200);
DISPLAY INVISIBLE (2675 3200);
FORCEPROP 1 LAST COMMENT_BODY TRUE
J 0
(2430 3055);
DISPLAY 0.872340 (2430 3055);
PAINT GREEN (2430 3055);
DISPLAY INVISIBLE (2430 3055);
FORCEPROP 1 LAST OFFPAGE TRUE
J 0
(2800 3025);
DISPLAY 0.872340 (2800 3025);
PAINT GREEN (2800 3025);
DISPLAY INVISIBLE (2800 3025);
FORCEPROP 2 LAST CDS_LIB standard
J 0
(2475 3150);
DISPLAY INVISIBLE (2475 3150);
FORCEADD OFFPAGE..2
(-3500 3000);
FORCEPROP 2 LAST $XR1 202 
J 0
(-3191 3000);
DISPLAY 0.638298 (-3191 3000);
PAINT MONO (-3191 3000);
FORCEPROP 2 LAST $XR0 183 
J 0
(-3311 3000);
DISPLAY 0.638298 (-3311 3000);
PAINT MONO (-3311 3000);
FORCEPROP 1 LAST COMMENT_BODY TRUE
J 0
(-3545 2905);
DISPLAY 0.872340 (-3545 2905);
PAINT GREEN (-3545 2905);
DISPLAY INVISIBLE (-3545 2905);
FORCEPROP 1 LAST OFFPAGE TRUE
J 0
(-3175 2875);
DISPLAY 0.872340 (-3175 2875);
PAINT GREEN (-3175 2875);
DISPLAY INVISIBLE (-3175 2875);
FORCEPROP 2 LAST CDS_LIB standard
J 0
(-3500 3000);
DISPLAY INVISIBLE (-3500 3000);
FORCEPROP 2 LAST PATH I30
J 0
(-3300 3050);
DISPLAY 1.021277 (-3300 3050);
DISPLAY INVISIBLE (-3300 3050);
FORCEADD OFFPAGE..2
(-500 3025);
FORCEPROP 2 LAST $XR1 205 
J 0
(-191 3025);
DISPLAY 0.638298 (-191 3025);
PAINT MONO (-191 3025);
FORCEPROP 2 LAST $XR0 183 
J 0
(-311 3025);
DISPLAY 0.638298 (-311 3025);
PAINT MONO (-311 3025);
FORCEPROP 1 LAST COMMENT_BODY TRUE
J 0
(-545 2930);
DISPLAY 0.872340 (-545 2930);
PAINT GREEN (-545 2930);
DISPLAY INVISIBLE (-545 2930);
FORCEPROP 1 LAST OFFPAGE TRUE
J 0
(-175 2900);
DISPLAY 0.872340 (-175 2900);
PAINT GREEN (-175 2900);
DISPLAY INVISIBLE (-175 2900);
FORCEPROP 2 LAST CDS_LIB standard
J 0
(-500 3025);
DISPLAY INVISIBLE (-500 3025);
FORCEPROP 2 LAST PATH I33
J 0
(-300 3075);
DISPLAY 1.021277 (-300 3075);
DISPLAY INVISIBLE (-300 3075);
FORCEADD OFFPAGE..2
(-500 2900);
FORCEPROP 2 LAST $XR1 205 
J 0
(-191 2900);
DISPLAY 0.638298 (-191 2900);
PAINT MONO (-191 2900);
FORCEPROP 2 LAST $XR0 183 
J 0
(-311 2900);
DISPLAY 0.638298 (-311 2900);
PAINT MONO (-311 2900);
FORCEPROP 2 LAST CDS_LIB standard
J 0
(-500 2900);
DISPLAY INVISIBLE (-500 2900);
FORCEPROP 1 LAST OFFPAGE TRUE
J 0
(-175 2775);
DISPLAY 0.872340 (-175 2775);
PAINT GREEN (-175 2775);
DISPLAY INVISIBLE (-175 2775);
FORCEPROP 1 LAST COMMENT_BODY TRUE
J 0
(-545 2805);
DISPLAY 0.872340 (-545 2805);
PAINT GREEN (-545 2805);
DISPLAY INVISIBLE (-545 2805);
FORCEPROP 2 LAST PATH I34
J 0
(-325 2975);
DISPLAY 1.021277 (-325 2975);
DISPLAY INVISIBLE (-325 2975);
FORCEADD UNIVERSAL_POWER..1
(-2200 3450);
FORCEPROP 3 LASTPIN (-2200 3400) SIG_NAME P3V3_AUX\g
J 0
(-2190 3410);
DISPLAY 0.659574 (-2190 3410);
PAINT MONO (-2190 3410);
DISPLAY INVISIBLE (-2190 3410);
FORCEPROP 1 LAST HDL_POWER P3V3_AUX
J 1
(-2200 3500);
DISPLAY 0.872340 (-2200 3500);
PAINT GREEN (-2200 3500);
FORCEPROP 2 LAST CDS_LIB logical_power
J 0
(-2200 3450);
DISPLAY INVISIBLE (-2200 3450);
FORCEPROP 1 LAST PATH I39
J 0
(-2150 3475);
DISPLAY 0.872340 (-2150 3475);
PAINT AQUA (-2150 3475);
DISPLAY INVISIBLE (-2150 3475);
FORCEADD Q_RES..1
(1150 3025);
FORCEPROP 1 LAST PART_NUMBER CS31002FB08
J 0
(1000 3125);
DISPLAY 0.787234 (1000 3125);
DISPLAY INVISIBLE (1000 3125);
FORCEPROP 1 LAST MATERIAL CHIP
J 0
(1500 3025);
DISPLAY 0.638298 (1500 3025);
FORCEPROP 1 LAST VALUE 10K
J 2
(1375 3025);
DISPLAY 0.638298 (1375 3025);
FORCEPROP 1 LAST TOLERANCE 1%
J 0
(1400 3025);
DISPLAY 0.638298 (1400 3025);
FORCEPROP 1 LAST $LOCATION R1257
J 0
(900 3025);
DISPLAY 0.787234 (900 3025);
FORCEPROP 1 LASTPIN (1050 3025) $PN 1
J 0
(1062 3037);
DISPLAY 0.787234 (1062 3037);
FORCEPROP 1 LASTPIN (1250 3025) $PN 2
J 0
(1212 3037);
DISPLAY 0.787234 (1212 3037);
FORCEPROP 1 LAST PATH I4
J 0
(1100 3175);
DISPLAY 0.978723 (1100 3175);
PAINT WHITE (1100 3175);
DISPLAY INVISIBLE (1100 3175);
FORCEPROP 2 LAST CDS_LIB pure_quanta
J 0
(1150 3025);
PAINT MONO (1150 3025);
DISPLAY INVISIBLE (1150 3025);
FORCEPROP 1 LAST PACK_TYPE 0402LF
J 0
(1000 3200);
DISPLAY 0.787234 (1000 3200);
DISPLAY INVISIBLE (1000 3200);
FORCEPROP 1 LAST WATTAGE 1/16W
J 2
(1575 3200);
DISPLAY 0.787234 (1575 3200);
DISPLAY INVISIBLE (1575 3200);
FORCEPROP 2 LAST CDS_LOCATION R1257
J 0
(1100 3225);
DISPLAY 1.021277 (1100 3225);
DISPLAY INVISIBLE (1100 3225);
FORCEPROP 2 LAST $SEC 1
J 0
(1100 3225);
DISPLAY 0.680851 (1100 3225);
PAINT MONO (1100 3225);
DISPLAY INVISIBLE (1100 3225);
FORCEPROP 2 LAST CDS_SEC 1
J 0
(1100 3225);
DISPLAY 1.021277 (1100 3225);
DISPLAY INVISIBLE (1100 3225);
FORCEADD Q_RES..1
(-1850 3025);
FORCEPROP 1 LAST PART_NUMBER CS31002FB08
J 0
(-2000 3125);
DISPLAY 0.787234 (-2000 3125);
DISPLAY INVISIBLE (-2000 3125);
FORCEPROP 1 LAST MATERIAL CHIP
J 0
(-1500 3025);
DISPLAY 0.638298 (-1500 3025);
FORCEPROP 1 LAST TOLERANCE 1%
J 0
(-1600 3025);
DISPLAY 0.638298 (-1600 3025);
FORCEPROP 1 LAST VALUE 10K
J 2
(-1625 3025);
DISPLAY 0.638298 (-1625 3025);
FORCEPROP 1 LAST $LOCATION R1449
J 0
(-2100 3025);
DISPLAY 0.638298 (-2100 3025);
FORCEPROP 1 LASTPIN (-1950 3025) $PN 1
J 0
(-1938 3037);
DISPLAY 0.787234 (-1938 3037);
FORCEPROP 1 LASTPIN (-1750 3025) $PN 2
J 0
(-1788 3037);
DISPLAY 0.787234 (-1788 3037);
FORCEPROP 1 LAST PATH I41
J 0
(-1900 3175);
DISPLAY 0.978723 (-1900 3175);
PAINT WHITE (-1900 3175);
DISPLAY INVISIBLE (-1900 3175);
FORCEPROP 2 LAST CDS_LIB pure_quanta
J 0
(-1850 3025);
PAINT MONO (-1850 3025);
DISPLAY INVISIBLE (-1850 3025);
FORCEPROP 1 LAST WATTAGE 1/16W
J 2
(-1425 3200);
DISPLAY 0.787234 (-1425 3200);
DISPLAY INVISIBLE (-1425 3200);
FORCEPROP 1 LAST PACK_TYPE 0402LF
J 0
(-2000 3200);
DISPLAY 0.787234 (-2000 3200);
DISPLAY INVISIBLE (-2000 3200);
FORCEPROP 2 LAST CDS_LOCATION R1449
J 0
(-1900 3225);
DISPLAY 1.021277 (-1900 3225);
DISPLAY INVISIBLE (-1900 3225);
FORCEPROP 2 LAST $SEC 1
J 0
(-1900 3225);
DISPLAY 0.680851 (-1900 3225);
PAINT MONO (-1900 3225);
DISPLAY INVISIBLE (-1900 3225);
FORCEPROP 2 LAST CDS_SEC 1
J 0
(-1900 3225);
DISPLAY 1.021277 (-1900 3225);
DISPLAY INVISIBLE (-1900 3225);
FORCEADD Q_RES..1
(-1850 2900);
FORCEPROP 1 LAST PART_NUMBER CS31002FB08
J 0
(-2000 3000);
DISPLAY 0.787234 (-2000 3000);
DISPLAY INVISIBLE (-2000 3000);
FORCEPROP 1 LAST VALUE 10K
J 2
(-1625 2900);
DISPLAY 0.638298 (-1625 2900);
FORCEPROP 1 LAST MATERIAL CHIP
J 0
(-1500 2900);
DISPLAY 0.638298 (-1500 2900);
FORCEPROP 1 LAST TOLERANCE 1%
J 0
(-1600 2900);
DISPLAY 0.638298 (-1600 2900);
FORCEPROP 1 LAST $LOCATION R1450
J 0
(-2100 2900);
DISPLAY 0.638298 (-2100 2900);
FORCEPROP 1 LASTPIN (-1950 2900) $PN 1
J 0
(-1938 2912);
DISPLAY 0.787234 (-1938 2912);
FORCEPROP 1 LASTPIN (-1750 2900) $PN 2
J 0
(-1788 2912);
DISPLAY 0.787234 (-1788 2912);
FORCEPROP 1 LAST PACK_TYPE 0402LF
J 0
(-2000 3075);
DISPLAY 0.787234 (-2000 3075);
DISPLAY INVISIBLE (-2000 3075);
FORCEPROP 1 LAST WATTAGE 1/16W
J 2
(-1425 3075);
DISPLAY 0.787234 (-1425 3075);
DISPLAY INVISIBLE (-1425 3075);
FORCEPROP 2 LAST CDS_LIB pure_quanta
J 0
(-1850 2900);
PAINT MONO (-1850 2900);
DISPLAY INVISIBLE (-1850 2900);
FORCEPROP 1 LAST PATH I42
J 0
(-1900 3050);
DISPLAY 0.978723 (-1900 3050);
PAINT WHITE (-1900 3050);
DISPLAY INVISIBLE (-1900 3050);
FORCEPROP 2 LAST CDS_LOCATION R1450
J 0
(-1900 3100);
DISPLAY 1.021277 (-1900 3100);
DISPLAY INVISIBLE (-1900 3100);
FORCEPROP 2 LAST $SEC 1
J 0
(-1900 3100);
DISPLAY 0.680851 (-1900 3100);
PAINT MONO (-1900 3100);
DISPLAY INVISIBLE (-1900 3100);
FORCEPROP 2 LAST CDS_SEC 1
J 0
(-1900 3100);
DISPLAY 1.021277 (-1900 3100);
DISPLAY INVISIBLE (-1900 3100);
FORCEADD OFFPAGE..2
(2650 -850);
FORCEPROP 2 LAST $XR1 205 
J 0
(2959 -850);
DISPLAY 0.638298 (2959 -850);
PAINT MONO (2959 -850);
FORCEPROP 2 LAST $XR0 185 
J 0
(2839 -850);
DISPLAY 0.638298 (2839 -850);
PAINT MONO (2839 -850);
FORCEPROP 1 LAST COMMENT_BODY TRUE
J 0
(2605 -945);
DISPLAY 0.872340 (2605 -945);
PAINT GREEN (2605 -945);
DISPLAY INVISIBLE (2605 -945);
FORCEPROP 1 LAST OFFPAGE TRUE
J 0
(2975 -975);
DISPLAY 0.872340 (2975 -975);
PAINT GREEN (2975 -975);
DISPLAY INVISIBLE (2975 -975);
FORCEPROP 2 LAST CDS_LIB standard
J 0
(2650 -850);
DISPLAY INVISIBLE (2650 -850);
FORCEPROP 2 LAST PATH I44
J 0
(3000 -800);
DISPLAY 1.021277 (3000 -800);
DISPLAY INVISIBLE (3000 -800);
FORCEADD OFFPAGE..2
(2650 -975);
FORCEPROP 2 LAST $XR1 205 
J 0
(2959 -975);
DISPLAY 0.638298 (2959 -975);
PAINT MONO (2959 -975);
FORCEPROP 2 LAST $XR0 185 
J 0
(2839 -975);
DISPLAY 0.638298 (2839 -975);
PAINT MONO (2839 -975);
FORCEPROP 2 LAST CDS_LIB standard
J 0
(2650 -975);
DISPLAY INVISIBLE (2650 -975);
FORCEPROP 1 LAST OFFPAGE TRUE
J 0
(2975 -1100);
DISPLAY 0.872340 (2975 -1100);
PAINT GREEN (2975 -1100);
DISPLAY INVISIBLE (2975 -1100);
FORCEPROP 1 LAST COMMENT_BODY TRUE
J 0
(2605 -1070);
DISPLAY 0.872340 (2605 -1070);
PAINT GREEN (2605 -1070);
DISPLAY INVISIBLE (2605 -1070);
FORCEPROP 2 LAST PATH I45
J 0
(3000 -925);
DISPLAY 1.021277 (3000 -925);
DISPLAY INVISIBLE (3000 -925);
FORCEADD UNIVERSAL_POWER..1
(825 -575);
FORCEPROP 3 LASTPIN (825 -625) SIG_NAME P3V3_AUX\g
J 0
(835 -615);
DISPLAY 0.659574 (835 -615);
PAINT MONO (835 -615);
DISPLAY INVISIBLE (835 -615);
FORCEPROP 1 LAST HDL_POWER P3V3_AUX
J 1
(825 -525);
DISPLAY 0.872340 (825 -525);
PAINT GREEN (825 -525);
FORCEPROP 1 LAST PATH I49
J 0
(875 -550);
DISPLAY 0.872340 (875 -550);
PAINT AQUA (875 -550);
DISPLAY INVISIBLE (875 -550);
FORCEPROP 2 LAST CDS_LIB logical_power
J 0
(825 -575);
DISPLAY INVISIBLE (825 -575);
FORCEADD OFFPAGE..2
(2475 3025);
FORCEPROP 2 LAST $XR0 183 
J 0
(2664 3025);
DISPLAY 0.638298 (2664 3025);
PAINT MONO (2664 3025);
FORCEPROP 2 LAST CDS_LIB standard
J 0
(2475 3025);
DISPLAY INVISIBLE (2475 3025);
FORCEPROP 1 LAST OFFPAGE TRUE
J 0
(2800 2900);
DISPLAY 0.872340 (2800 2900);
PAINT GREEN (2800 2900);
DISPLAY INVISIBLE (2800 2900);
FORCEPROP 1 LAST COMMENT_BODY TRUE
J 0
(2430 2930);
DISPLAY 0.872340 (2430 2930);
PAINT GREEN (2430 2930);
DISPLAY INVISIBLE (2430 2930);
FORCEPROP 2 LAST PATH I5
J 0
(2675 3075);
DISPLAY 1.021277 (2675 3075);
DISPLAY INVISIBLE (2675 3075);
FORCEADD Q_RES..1
(1200 -850);
FORCEPROP 1 LAST PART_NUMBER CS31002FB08
J 0
(1050 -750);
DISPLAY 0.787234 (1050 -750);
DISPLAY INVISIBLE (1050 -750);
FORCEPROP 1 LAST VALUE 10K
J 2
(1425 -850);
DISPLAY 0.638298 (1425 -850);
FORCEPROP 1 LAST TOLERANCE 1%
J 0
(1450 -850);
DISPLAY 0.638298 (1450 -850);
FORCEPROP 1 LAST MATERIAL CHIP
J 0
(1550 -850);
DISPLAY 0.638298 (1550 -850);
FORCEPROP 1 LAST WATTAGE 1/16W
J 2
(1625 -675);
DISPLAY 0.787234 (1625 -675);
FORCEPROP 1 LAST PACK_TYPE 0402LF
J 0
(1050 -675);
DISPLAY 0.787234 (1050 -675);
FORCEPROP 1 LAST $LOCATION R1458
J 0
(925 -850);
DISPLAY 0.638298 (925 -850);
FORCEPROP 1 LASTPIN (1100 -850) $PN 1
J 0
(1112 -838);
DISPLAY 0.787234 (1112 -838);
FORCEPROP 1 LASTPIN (1300 -850) $PN 2
J 0
(1262 -838);
DISPLAY 0.787234 (1262 -838);
FORCEPROP 1 LAST PATH I50
J 0
(1150 -700);
DISPLAY 0.978723 (1150 -700);
PAINT WHITE (1150 -700);
DISPLAY INVISIBLE (1150 -700);
FORCEPROP 2 LAST CDS_LIB pure_quanta
J 0
(1200 -850);
PAINT MONO (1200 -850);
DISPLAY INVISIBLE (1200 -850);
FORCEPROP 2 LAST CDS_LOCATION R1458
J 0
(1625 -625);
DISPLAY 1.021277 (1625 -625);
DISPLAY INVISIBLE (1625 -625);
FORCEPROP 2 LAST $SEC 1
J 0
(1625 -625);
DISPLAY 0.680851 (1625 -625);
PAINT MONO (1625 -625);
DISPLAY INVISIBLE (1625 -625);
FORCEPROP 2 LAST CDS_SEC 1
J 0
(1625 -625);
DISPLAY 1.021277 (1625 -625);
DISPLAY INVISIBLE (1625 -625);
FORCEADD Q_RES..1
(1200 -975);
FORCEPROP 1 LAST PART_NUMBER CS31002FB08
J 0
(1050 -875);
DISPLAY 0.787234 (1050 -875);
DISPLAY INVISIBLE (1050 -875);
FORCEPROP 1 LAST VALUE 10K
J 2
(1425 -975);
DISPLAY 0.638298 (1425 -975);
FORCEPROP 1 LAST TOLERANCE 1%
J 0
(1450 -975);
DISPLAY 0.638298 (1450 -975);
FORCEPROP 1 LAST MATERIAL CHIP
J 0
(1550 -975);
DISPLAY 0.638298 (1550 -975);
FORCEPROP 1 LAST $LOCATION R1459
J 0
(925 -975);
DISPLAY 0.638298 (925 -975);
FORCEPROP 1 LASTPIN (1100 -975) $PN 1
J 0
(1112 -963);
DISPLAY 0.787234 (1112 -963);
FORCEPROP 1 LASTPIN (1300 -975) $PN 2
J 0
(1262 -963);
DISPLAY 0.787234 (1262 -963);
FORCEPROP 1 LAST WATTAGE 1/16W
J 2
(1625 -800);
DISPLAY 0.787234 (1625 -800);
DISPLAY INVISIBLE (1625 -800);
FORCEPROP 1 LAST PACK_TYPE 0402LF
J 0
(1050 -800);
DISPLAY 0.787234 (1050 -800);
DISPLAY INVISIBLE (1050 -800);
FORCEPROP 1 LAST PATH I51
J 0
(1150 -825);
DISPLAY 0.978723 (1150 -825);
PAINT WHITE (1150 -825);
DISPLAY INVISIBLE (1150 -825);
FORCEPROP 2 LAST CDS_LIB pure_quanta
J 0
(1200 -975);
PAINT MONO (1200 -975);
DISPLAY INVISIBLE (1200 -975);
FORCEPROP 2 LAST CDS_LOCATION R1459
J 0
(1150 -775);
DISPLAY 1.021277 (1150 -775);
DISPLAY INVISIBLE (1150 -775);
FORCEPROP 2 LAST $SEC 1
J 0
(1150 -775);
DISPLAY 0.680851 (1150 -775);
PAINT MONO (1150 -775);
DISPLAY INVISIBLE (1150 -775);
FORCEPROP 2 LAST CDS_SEC 1
J 0
(1150 -775);
DISPLAY 1.021277 (1150 -775);
DISPLAY INVISIBLE (1150 -775);
FORCEADD OFFPAGE..2
(-3500 1300);
FORCEPROP 2 LAST $XR1 205 
J 0
(-3191 1300);
DISPLAY 0.638298 (-3191 1300);
PAINT MONO (-3191 1300);
FORCEPROP 2 LAST $XR0 184 
J 0
(-3311 1300);
DISPLAY 0.638298 (-3311 1300);
PAINT MONO (-3311 1300);
FORCEPROP 1 LAST COMMENT_BODY TRUE
J 0
(-3545 1205);
DISPLAY 0.872340 (-3545 1205);
PAINT GREEN (-3545 1205);
DISPLAY INVISIBLE (-3545 1205);
FORCEPROP 1 LAST OFFPAGE TRUE
J 0
(-3175 1175);
DISPLAY 0.872340 (-3175 1175);
PAINT GREEN (-3175 1175);
DISPLAY INVISIBLE (-3175 1175);
FORCEPROP 2 LAST CDS_LIB standard
J 0
(-3500 1300);
DISPLAY INVISIBLE (-3500 1300);
FORCEPROP 2 LAST PATH I53
J 0
(-3150 1350);
DISPLAY 1.021277 (-3150 1350);
DISPLAY INVISIBLE (-3150 1350);
FORCEADD OFFPAGE..2
(-3500 1175);
FORCEPROP 2 LAST $XR1 215 
J 0
(-3191 1175);
DISPLAY 0.638298 (-3191 1175);
PAINT MONO (-3191 1175);
FORCEPROP 2 LAST $XR0 184 
J 0
(-3311 1175);
DISPLAY 0.638298 (-3311 1175);
PAINT MONO (-3311 1175);
FORCEPROP 2 LAST PATH I54
J 0
(-3150 1225);
DISPLAY 1.021277 (-3150 1225);
DISPLAY INVISIBLE (-3150 1225);
FORCEPROP 2 LAST CDS_LIB standard
J 0
(-3500 1175);
DISPLAY INVISIBLE (-3500 1175);
FORCEPROP 1 LAST OFFPAGE TRUE
J 0
(-3175 1050);
DISPLAY 0.872340 (-3175 1050);
PAINT GREEN (-3175 1050);
DISPLAY INVISIBLE (-3175 1050);
FORCEPROP 1 LAST COMMENT_BODY TRUE
J 0
(-3545 1080);
DISPLAY 0.872340 (-3545 1080);
PAINT GREEN (-3545 1080);
DISPLAY INVISIBLE (-3545 1080);
FORCEADD UNIVERSAL_POWER..1
(-5300 1600);
FORCEPROP 3 LASTPIN (-5300 1550) SIG_NAME P3V3_AUX\g
J 0
(-5290 1560);
DISPLAY 0.659574 (-5290 1560);
PAINT MONO (-5290 1560);
DISPLAY INVISIBLE (-5290 1560);
FORCEPROP 1 LAST HDL_POWER P3V3_AUX
J 1
(-5300 1650);
DISPLAY 0.872340 (-5300 1650);
PAINT GREEN (-5300 1650);
FORCEPROP 2 LAST CDS_LIB logical_power
J 0
(-5300 1600);
DISPLAY INVISIBLE (-5300 1600);
FORCEPROP 1 LAST PATH I58
J 0
(-5250 1625);
DISPLAY 0.872340 (-5250 1625);
PAINT AQUA (-5250 1625);
DISPLAY INVISIBLE (-5250 1625);
FORCEADD Q_RES..1
(-4950 1300);
FORCEPROP 1 LAST PART_NUMBER CS31002FB08
J 0
(-5100 1400);
DISPLAY 0.787234 (-5100 1400);
DISPLAY INVISIBLE (-5100 1400);
FORCEPROP 1 LAST MATERIAL CHIP
J 0
(-4625 1300);
DISPLAY 0.638298 (-4625 1300);
FORCEPROP 1 LAST WATTAGE 1/16W
J 2
(-4525 1475);
DISPLAY 0.787234 (-4525 1475);
FORCEPROP 1 LAST PACK_TYPE 0402LF
J 0
(-5100 1475);
DISPLAY 0.787234 (-5100 1475);
FORCEPROP 1 LAST TOLERANCE 1%
J 0
(-4725 1300);
DISPLAY 0.638298 (-4725 1300);
FORCEPROP 1 LAST VALUE 10K
J 2
(-4750 1300);
DISPLAY 0.638298 (-4750 1300);
FORCEPROP 1 LAST $LOCATION R8
J 0
(-5175 1300);
DISPLAY 0.638298 (-5175 1300);
FORCEPROP 1 LASTPIN (-5050 1300) $PN 1
J 0
(-5038 1312);
DISPLAY 0.787234 (-5038 1312);
FORCEPROP 1 LASTPIN (-4850 1300) $PN 2
J 0
(-4888 1312);
DISPLAY 0.787234 (-4888 1312);
FORCEPROP 2 LAST CDS_LIB pure_quanta
J 0
(-4950 1300);
PAINT MONO (-4950 1300);
DISPLAY INVISIBLE (-4950 1300);
FORCEPROP 1 LAST PATH I59
J 0
(-5000 1450);
DISPLAY 0.978723 (-5000 1450);
PAINT WHITE (-5000 1450);
DISPLAY INVISIBLE (-5000 1450);
FORCEPROP 2 LAST CDS_LOCATION R8
J 0
(-4525 1525);
DISPLAY 1.021277 (-4525 1525);
DISPLAY INVISIBLE (-4525 1525);
FORCEPROP 2 LAST $SEC 1
J 0
(-4525 1525);
DISPLAY 0.680851 (-4525 1525);
PAINT MONO (-4525 1525);
DISPLAY INVISIBLE (-4525 1525);
FORCEPROP 2 LAST CDS_SEC 1
J 0
(-4525 1525);
DISPLAY 1.021277 (-4525 1525);
DISPLAY INVISIBLE (-4525 1525);
FORCEADD Q_RES..1
(1150 2875);
FORCEPROP 1 LAST PART_NUMBER CS31002FB08
J 0
(1000 2975);
DISPLAY 0.787234 (1000 2975);
DISPLAY INVISIBLE (1000 2975);
FORCEPROP 1 LAST VALUE 10K
J 2
(1375 2875);
DISPLAY 0.638298 (1375 2875);
FORCEPROP 1 LAST TOLERANCE 1%
J 0
(1400 2875);
DISPLAY 0.638298 (1400 2875);
FORCEPROP 1 LAST MATERIAL CHIP
J 0
(1500 2875);
DISPLAY 0.638298 (1500 2875);
FORCEPROP 1 LAST $LOCATION R3041
J 0
(900 2875);
DISPLAY 0.787234 (900 2875);
FORCEPROP 1 LASTPIN (1050 2875) $PN 1
J 0
(1062 2887);
DISPLAY 0.787234 (1062 2887);
FORCEPROP 1 LASTPIN (1250 2875) $PN 2
J 0
(1212 2887);
DISPLAY 0.787234 (1212 2887);
FORCEPROP 1 LAST PATH I6
J 0
(1100 3025);
DISPLAY 0.978723 (1100 3025);
PAINT WHITE (1100 3025);
DISPLAY INVISIBLE (1100 3025);
FORCEPROP 1 LAST WATTAGE 1/16W
J 2
(1575 3050);
DISPLAY 0.787234 (1575 3050);
DISPLAY INVISIBLE (1575 3050);
FORCEPROP 1 LAST PACK_TYPE 0402LF
J 0
(1000 3050);
DISPLAY 0.787234 (1000 3050);
DISPLAY INVISIBLE (1000 3050);
FORCEPROP 2 LAST CDS_LIB pure_quanta
J 0
(1150 2875);
PAINT MONO (1150 2875);
DISPLAY INVISIBLE (1150 2875);
FORCEPROP 2 LAST CDS_LOCATION R3041
J 0
(1100 3075);
DISPLAY 1.021277 (1100 3075);
DISPLAY INVISIBLE (1100 3075);
FORCEPROP 2 LAST $SEC 1
J 0
(1100 3075);
DISPLAY 0.680851 (1100 3075);
PAINT MONO (1100 3075);
DISPLAY INVISIBLE (1100 3075);
FORCEPROP 2 LAST CDS_SEC 1
J 0
(1100 3075);
DISPLAY 1.021277 (1100 3075);
DISPLAY INVISIBLE (1100 3075);
FORCEADD Q_RES..1
(-4950 1175);
FORCEPROP 1 LAST PART_NUMBER CS31002FB08
J 0
(-5100 1275);
DISPLAY 0.787234 (-5100 1275);
DISPLAY INVISIBLE (-5100 1275);
FORCEPROP 1 LAST TOLERANCE 1%
J 0
(-4725 1175);
DISPLAY 0.638298 (-4725 1175);
FORCEPROP 1 LAST VALUE 10K
J 2
(-4750 1175);
DISPLAY 0.638298 (-4750 1175);
FORCEPROP 1 LAST MATERIAL CHIP
J 0
(-4625 1175);
DISPLAY 0.638298 (-4625 1175);
FORCEPROP 1 LAST $LOCATION R71
J 0
(-5175 1175);
DISPLAY 0.638298 (-5175 1175);
FORCEPROP 1 LASTPIN (-5050 1175) $PN 1
J 0
(-5038 1187);
DISPLAY 0.787234 (-5038 1187);
FORCEPROP 1 LASTPIN (-4850 1175) $PN 2
J 0
(-4888 1187);
DISPLAY 0.787234 (-4888 1187);
FORCEPROP 2 LAST CDS_LIB pure_quanta
J 0
(-4950 1175);
PAINT MONO (-4950 1175);
DISPLAY INVISIBLE (-4950 1175);
FORCEPROP 1 LAST PATH I60
J 0
(-5000 1325);
DISPLAY 0.978723 (-5000 1325);
PAINT WHITE (-5000 1325);
DISPLAY INVISIBLE (-5000 1325);
FORCEPROP 1 LAST PACK_TYPE 0402LF
J 0
(-5100 1350);
DISPLAY 0.787234 (-5100 1350);
DISPLAY INVISIBLE (-5100 1350);
FORCEPROP 1 LAST WATTAGE 1/16W
J 2
(-4525 1350);
DISPLAY 0.787234 (-4525 1350);
DISPLAY INVISIBLE (-4525 1350);
FORCEPROP 2 LAST CDS_LOCATION R71
J 0
(-5000 1375);
DISPLAY 1.021277 (-5000 1375);
DISPLAY INVISIBLE (-5000 1375);
FORCEPROP 2 LAST $SEC 1
J 0
(-5000 1375);
DISPLAY 0.680851 (-5000 1375);
PAINT MONO (-5000 1375);
DISPLAY INVISIBLE (-5000 1375);
FORCEPROP 2 LAST CDS_SEC 1
J 0
(-5000 1375);
DISPLAY 1.021277 (-5000 1375);
DISPLAY INVISIBLE (-5000 1375);
FORCEADD OFFPAGE..2
(-3500 1050);
FORCEPROP 2 LAST $XR1 215 
J 0
(-3191 1050);
DISPLAY 0.638298 (-3191 1050);
PAINT MONO (-3191 1050);
FORCEPROP 2 LAST $XR0 184 
J 0
(-3311 1050);
DISPLAY 0.638298 (-3311 1050);
PAINT MONO (-3311 1050);
FORCEPROP 2 LAST CDS_LIB standard
J 0
(-3500 1050);
DISPLAY INVISIBLE (-3500 1050);
FORCEPROP 1 LAST OFFPAGE TRUE
J 0
(-3175 925);
DISPLAY 0.872340 (-3175 925);
PAINT GREEN (-3175 925);
DISPLAY INVISIBLE (-3175 925);
FORCEPROP 1 LAST COMMENT_BODY TRUE
J 0
(-3545 955);
DISPLAY 0.872340 (-3545 955);
PAINT GREEN (-3545 955);
DISPLAY INVISIBLE (-3545 955);
FORCEPROP 2 LAST PATH I61
J 0
(-3150 1100);
DISPLAY 1.021277 (-3150 1100);
DISPLAY INVISIBLE (-3150 1100);
FORCEADD Q_RES..1
(-4950 1050);
FORCEPROP 1 LAST PART_NUMBER CS31002FB08
J 0
(-5100 1150);
DISPLAY 0.787234 (-5100 1150);
DISPLAY INVISIBLE (-5100 1150);
FORCEPROP 1 LAST MATERIAL CHIP
J 0
(-4625 1050);
DISPLAY 0.638298 (-4625 1050);
FORCEPROP 1 LAST TOLERANCE 1%
J 0
(-4725 1050);
DISPLAY 0.638298 (-4725 1050);
FORCEPROP 1 LAST VALUE 10K
J 2
(-4750 1050);
DISPLAY 0.638298 (-4750 1050);
FORCEPROP 1 LAST $LOCATION R1554
J 0
(-5175 1050);
DISPLAY 0.638298 (-5175 1050);
FORCEPROP 1 LASTPIN (-5050 1050) $PN 1
J 0
(-5038 1062);
DISPLAY 0.787234 (-5038 1062);
FORCEPROP 1 LASTPIN (-4850 1050) $PN 2
J 0
(-4888 1062);
DISPLAY 0.787234 (-4888 1062);
FORCEPROP 2 LAST CDS_LIB pure_quanta
J 0
(-4950 1050);
PAINT MONO (-4950 1050);
DISPLAY INVISIBLE (-4950 1050);
FORCEPROP 1 LAST PACK_TYPE 0402LF
J 0
(-5100 1225);
DISPLAY 0.787234 (-5100 1225);
DISPLAY INVISIBLE (-5100 1225);
FORCEPROP 1 LAST WATTAGE 1/16W
J 2
(-4525 1225);
DISPLAY 0.787234 (-4525 1225);
DISPLAY INVISIBLE (-4525 1225);
FORCEPROP 1 LAST PATH I62
J 0
(-5000 1200);
DISPLAY 0.978723 (-5000 1200);
PAINT WHITE (-5000 1200);
DISPLAY INVISIBLE (-5000 1200);
FORCEPROP 2 LAST CDS_LOCATION R1554
J 0
(-5000 1250);
DISPLAY 1.021277 (-5000 1250);
DISPLAY INVISIBLE (-5000 1250);
FORCEPROP 2 LAST $SEC 1
J 0
(-5000 1250);
DISPLAY 0.680851 (-5000 1250);
PAINT MONO (-5000 1250);
DISPLAY INVISIBLE (-5000 1250);
FORCEPROP 2 LAST CDS_SEC 1
J 0
(-5000 1250);
DISPLAY 1.021277 (-5000 1250);
DISPLAY INVISIBLE (-5000 1250);
FORCEADD OFFPAGE..2
(-400 1300);
FORCEPROP 2 LAST $XR0 184 
J 0
(-211 1300);
DISPLAY 0.638298 (-211 1300);
PAINT MONO (-211 1300);
FORCEPROP 2 LAST CDS_LIB standard
J 0
(-400 1300);
DISPLAY INVISIBLE (-400 1300);
FORCEPROP 1 LAST OFFPAGE TRUE
J 0
(-75 1175);
DISPLAY 0.872340 (-75 1175);
PAINT GREEN (-75 1175);
DISPLAY INVISIBLE (-75 1175);
FORCEPROP 1 LAST COMMENT_BODY TRUE
J 0
(-445 1205);
DISPLAY 0.872340 (-445 1205);
PAINT GREEN (-445 1205);
DISPLAY INVISIBLE (-445 1205);
FORCEPROP 2 LAST PATH I64
J 0
(-50 1350);
DISPLAY 1.021277 (-50 1350);
DISPLAY INVISIBLE (-50 1350);
FORCEADD UNIVERSAL_POWER..1
(-2200 1600);
FORCEPROP 3 LASTPIN (-2200 1550) SIG_NAME P3V3_AUX\g
J 0
(-2190 1560);
DISPLAY 0.659574 (-2190 1560);
PAINT MONO (-2190 1560);
DISPLAY INVISIBLE (-2190 1560);
FORCEPROP 1 LAST HDL_POWER P3V3_AUX
J 1
(-2200 1650);
DISPLAY 0.872340 (-2200 1650);
PAINT GREEN (-2200 1650);
FORCEPROP 2 LAST CDS_LIB logical_power
J 0
(-2200 1600);
DISPLAY INVISIBLE (-2200 1600);
FORCEPROP 1 LAST PATH I65
J 0
(-2150 1625);
DISPLAY 0.872340 (-2150 1625);
PAINT AQUA (-2150 1625);
DISPLAY INVISIBLE (-2150 1625);
FORCEADD Q_RES..1
(-1850 1300);
FORCEPROP 1 LAST PART_NUMBER CS31002FB08
J 0
(-2000 1400);
DISPLAY 0.787234 (-2000 1400);
DISPLAY INVISIBLE (-2000 1400);
FORCEPROP 1 LAST PACK_TYPE 0402LF
J 0
(-2000 1475);
DISPLAY 0.787234 (-2000 1475);
FORCEPROP 1 LAST WATTAGE 1/16W
J 2
(-1425 1475);
DISPLAY 0.787234 (-1425 1475);
FORCEPROP 1 LAST MATERIAL CHIP
J 0
(-1525 1300);
DISPLAY 0.638298 (-1525 1300);
FORCEPROP 1 LAST VALUE 10K
J 2
(-1650 1300);
DISPLAY 0.638298 (-1650 1300);
FORCEPROP 1 LAST TOLERANCE 1%
J 0
(-1625 1300);
DISPLAY 0.638298 (-1625 1300);
FORCEPROP 1 LAST $LOCATION R456
J 0
(-2125 1300);
DISPLAY 0.787234 (-2125 1300);
FORCEPROP 1 LASTPIN (-1950 1300) $PN 1
J 0
(-1938 1312);
DISPLAY 0.787234 (-1938 1312);
PAINT MONO (-1938 1312);
FORCEPROP 1 LASTPIN (-1750 1300) $PN 2
J 0
(-1788 1312);
DISPLAY 0.787234 (-1788 1312);
PAINT MONO (-1788 1312);
FORCEPROP 1 LAST PATH I66
J 0
(-1900 1450);
DISPLAY 0.978723 (-1900 1450);
PAINT WHITE (-1900 1450);
DISPLAY INVISIBLE (-1900 1450);
FORCEPROP 2 LAST CDS_LIB pure_quanta
J 0
(-1850 1300);
DISPLAY INVISIBLE (-1850 1300);
FORCEPROP 0 LAST CDS_LOCATION R456
J 0
(-1425 1525);
DISPLAY 1.021277 (-1425 1525);
DISPLAY INVISIBLE (-1425 1525);
FORCEPROP 0 LAST $SEC 1
J 0
(-1425 1525);
DISPLAY 0.680851 (-1425 1525);
PAINT MONO (-1425 1525);
DISPLAY INVISIBLE (-1425 1525);
FORCEPROP 0 LAST CDS_SEC 1
J 0
(-1425 1525);
DISPLAY 1.021277 (-1425 1525);
DISPLAY INVISIBLE (-1425 1525);
FORCEADD UNIVERSAL_POWER..1
(-5300 -550);
FORCEPROP 3 LASTPIN (-5300 -600) SIG_NAME P3V3_AUX\g
J 0
(-5290 -590);
DISPLAY 0.659574 (-5290 -590);
PAINT MONO (-5290 -590);
DISPLAY INVISIBLE (-5290 -590);
FORCEPROP 1 LAST HDL_POWER P3V3_AUX
J 1
(-5300 -500);
DISPLAY 0.872340 (-5300 -500);
PAINT GREEN (-5300 -500);
FORCEPROP 1 LAST PATH I67
J 0
(-5250 -525);
DISPLAY 0.872340 (-5250 -525);
PAINT AQUA (-5250 -525);
DISPLAY INVISIBLE (-5250 -525);
FORCEPROP 2 LAST CDS_LIB logical_power
J 0
(-5300 -550);
DISPLAY INVISIBLE (-5300 -550);
FORCEADD OFFPAGE..2
(-3650 -850);
FORCEPROP 2 LAST $XR1 184 
J 0
(-3341 -850);
DISPLAY 0.638298 (-3341 -850);
PAINT MONO (-3341 -850);
FORCEPROP 2 LAST $XR0 215 
J 0
(-3461 -850);
DISPLAY 0.638298 (-3461 -850);
PAINT MONO (-3461 -850);
FORCEPROP 2 LAST PATH I68
J 0
(-3300 -800);
DISPLAY 1.021277 (-3300 -800);
DISPLAY INVISIBLE (-3300 -800);
FORCEPROP 2 LAST CDS_LIB standard
J 0
(-3650 -850);
DISPLAY INVISIBLE (-3650 -850);
FORCEPROP 1 LAST OFFPAGE TRUE
J 0
(-3325 -975);
DISPLAY 0.872340 (-3325 -975);
PAINT GREEN (-3325 -975);
DISPLAY INVISIBLE (-3325 -975);
FORCEPROP 1 LAST COMMENT_BODY TRUE
J 0
(-3695 -945);
DISPLAY 0.872340 (-3695 -945);
PAINT GREEN (-3695 -945);
DISPLAY INVISIBLE (-3695 -945);
FORCEADD Q_RES..1
(-4925 -850);
FORCEPROP 1 LAST PART_NUMBER CS31002FB08
J 0
(-5075 -750);
DISPLAY 0.638298 (-5075 -750);
DISPLAY INVISIBLE (-5075 -750);
FORCEPROP 1 LAST WATTAGE 1/16W
J 2
(-4500 -675);
DISPLAY 0.638298 (-4500 -675);
FORCEPROP 1 LAST VALUE 10K
J 2
(-4700 -850);
DISPLAY 0.638298 (-4700 -850);
FORCEPROP 1 LAST TOLERANCE 1%
J 0
(-4675 -850);
DISPLAY 0.638298 (-4675 -850);
FORCEPROP 1 LAST PACK_TYPE 0402LF
J 0
(-5075 -675);
DISPLAY 0.638298 (-5075 -675);
FORCEPROP 1 LAST MATERIAL EMPTY
J 0
(-4575 -850);
DISPLAY 0.638298 (-4575 -850);
PAINT RED (-4575 -850);
FORCEPROP 1 LAST $LOCATION R401
J 0
(-5150 -850);
DISPLAY 0.638298 (-5150 -850);
FORCEPROP 1 LASTPIN (-5025 -850) $PN 1
J 0
(-5013 -838);
DISPLAY 0.787234 (-5013 -838);
PAINT MONO (-5013 -838);
FORCEPROP 1 LASTPIN (-4825 -850) $PN 2
J 0
(-4863 -838);
DISPLAY 0.787234 (-4863 -838);
PAINT MONO (-4863 -838);
FORCEPROP 2 LAST CDS_LIB pure_quanta
J 0
(-4925 -850);
DISPLAY INVISIBLE (-4925 -850);
FORCEPROP 1 LAST PATH I69
J 0
(-4975 -700);
DISPLAY 0.978723 (-4975 -700);
PAINT WHITE (-4975 -700);
DISPLAY INVISIBLE (-4975 -700);
FORCEPROP 0 LAST CDS_LOCATION R401
J 0
(-4500 -625);
DISPLAY 1.021277 (-4500 -625);
DISPLAY INVISIBLE (-4500 -625);
FORCEPROP 0 LAST $SEC 1
J 0
(-4500 -625);
DISPLAY 0.680851 (-4500 -625);
PAINT MONO (-4500 -625);
DISPLAY INVISIBLE (-4500 -625);
FORCEPROP 0 LAST CDS_SEC 1
J 0
(-4500 -625);
DISPLAY 1.021277 (-4500 -625);
DISPLAY INVISIBLE (-4500 -625);
FORCEADD OFFPAGE..2
(2475 2875);
FORCEPROP 2 LAST $XR1 205 
J 0
(2784 2875);
DISPLAY 0.638298 (2784 2875);
PAINT MONO (2784 2875);
FORCEPROP 2 LAST $XR0 183 
J 0
(2664 2875);
DISPLAY 0.638298 (2664 2875);
PAINT MONO (2664 2875);
FORCEPROP 1 LAST COMMENT_BODY TRUE
J 0
(2430 2780);
DISPLAY 0.872340 (2430 2780);
PAINT GREEN (2430 2780);
DISPLAY INVISIBLE (2430 2780);
FORCEPROP 1 LAST OFFPAGE TRUE
J 0
(2800 2750);
DISPLAY 0.872340 (2800 2750);
PAINT GREEN (2800 2750);
DISPLAY INVISIBLE (2800 2750);
FORCEPROP 2 LAST CDS_LIB standard
J 0
(2475 2875);
DISPLAY INVISIBLE (2475 2875);
FORCEPROP 2 LAST PATH I7
J 0
(2675 2925);
DISPLAY 1.021277 (2675 2925);
DISPLAY INVISIBLE (2675 2925);
FORCEADD OFFPAGE..2
(2475 2625);
FORCEPROP 2 LAST $XR0 183 
J 0
(2664 2625);
DISPLAY 0.638298 (2664 2625);
PAINT MONO (2664 2625);
FORCEPROP 2 LAST PATH I71
J 0
(2675 2675);
DISPLAY 1.021277 (2675 2675);
DISPLAY INVISIBLE (2675 2675);
FORCEPROP 2 LAST CDS_LIB standard
J 0
(2475 2625);
DISPLAY INVISIBLE (2475 2625);
FORCEPROP 1 LAST OFFPAGE TRUE
J 0
(2800 2500);
DISPLAY 0.872340 (2800 2500);
PAINT GREEN (2800 2500);
DISPLAY INVISIBLE (2800 2500);
FORCEPROP 1 LAST COMMENT_BODY TRUE
J 0
(2430 2530);
DISPLAY 0.872340 (2430 2530);
PAINT GREEN (2430 2530);
DISPLAY INVISIBLE (2430 2530);
FORCEADD Q_RES..1
(1150 2625);
FORCEPROP 1 LAST PART_NUMBER CS31002FB08
J 0
(1000 2725);
DISPLAY 0.787234 (1000 2725);
DISPLAY INVISIBLE (1000 2725);
FORCEPROP 1 LAST MATERIAL CHIP
J 0
(1500 2625);
DISPLAY 0.638298 (1500 2625);
FORCEPROP 1 LAST TOLERANCE 1%
J 0
(1400 2625);
DISPLAY 0.638298 (1400 2625);
FORCEPROP 1 LAST VALUE 10K
J 2
(1375 2625);
DISPLAY 0.638298 (1375 2625);
FORCEPROP 1 LAST $LOCATION R1955
J 0
(900 2625);
DISPLAY 0.787234 (900 2625);
FORCEPROP 1 LASTPIN (1050 2625) $PN 1
J 0
(1062 2637);
DISPLAY 0.787234 (1062 2637);
PAINT MONO (1062 2637);
FORCEPROP 1 LASTPIN (1250 2625) $PN 2
J 0
(1212 2637);
DISPLAY 0.787234 (1212 2637);
PAINT MONO (1212 2637);
FORCEPROP 2 LAST CDS_LIB pure_quanta
J 0
(1150 2625);
DISPLAY INVISIBLE (1150 2625);
FORCEPROP 1 LAST PATH I72
J 0
(1100 2775);
DISPLAY 0.978723 (1100 2775);
PAINT WHITE (1100 2775);
DISPLAY INVISIBLE (1100 2775);
FORCEPROP 1 LAST WATTAGE 1/16W
J 2
(1575 2800);
DISPLAY 0.787234 (1575 2800);
DISPLAY INVISIBLE (1575 2800);
FORCEPROP 1 LAST PACK_TYPE 0402LF
J 0
(1000 2800);
DISPLAY 0.787234 (1000 2800);
DISPLAY INVISIBLE (1000 2800);
FORCEPROP 0 LAST CDS_LOCATION R1955
J 0
(1500 2675);
DISPLAY 1.021277 (1500 2675);
DISPLAY INVISIBLE (1500 2675);
FORCEPROP 0 LAST $SEC 1
J 0
(1500 2675);
DISPLAY 0.680851 (1500 2675);
PAINT MONO (1500 2675);
DISPLAY INVISIBLE (1500 2675);
FORCEPROP 0 LAST CDS_SEC 1
J 0
(1500 2675);
DISPLAY 1.021277 (1500 2675);
DISPLAY INVISIBLE (1500 2675);
FORCEADD OFFPAGE..2
(-3500 925);
FORCEPROP 2 LAST $XR1 184 
J 0
(-3191 925);
DISPLAY 0.638298 (-3191 925);
PAINT MONO (-3191 925);
FORCEPROP 2 LAST $XR0 215 
J 0
(-3311 925);
DISPLAY 0.638298 (-3311 925);
PAINT MONO (-3311 925);
FORCEPROP 2 LAST PATH I74
J 0
(-3150 975);
DISPLAY 1.021277 (-3150 975);
DISPLAY INVISIBLE (-3150 975);
FORCEPROP 1 LAST COMMENT_BODY TRUE
J 0
(-3545 830);
DISPLAY 0.872340 (-3545 830);
PAINT GREEN (-3545 830);
DISPLAY INVISIBLE (-3545 830);
FORCEPROP 1 LAST OFFPAGE TRUE
J 0
(-3175 800);
DISPLAY 0.872340 (-3175 800);
PAINT GREEN (-3175 800);
DISPLAY INVISIBLE (-3175 800);
FORCEPROP 2 LAST CDS_LIB standard
J 0
(-3500 925);
DISPLAY INVISIBLE (-3500 925);
FORCEADD Q_RES..1
(-4950 925);
FORCEPROP 1 LAST PART_NUMBER CS31002FB08
J 0
(-5100 1025);
DISPLAY 0.787234 (-5100 1025);
DISPLAY INVISIBLE (-5100 1025);
FORCEPROP 1 LAST MATERIAL CHIP
J 0
(-4625 925);
DISPLAY 0.638298 (-4625 925);
FORCEPROP 1 LAST TOLERANCE 1%
J 0
(-4725 925);
DISPLAY 0.638298 (-4725 925);
FORCEPROP 1 LAST VALUE 10K
J 2
(-4750 925);
DISPLAY 0.638298 (-4750 925);
FORCEPROP 1 LAST $LOCATION R2342
J 0
(-5175 925);
DISPLAY 0.638298 (-5175 925);
FORCEPROP 1 LASTPIN (-5050 925) $PN 1
J 0
(-5038 937);
DISPLAY 0.787234 (-5038 937);
PAINT MONO (-5038 937);
FORCEPROP 1 LASTPIN (-4850 925) $PN 2
J 0
(-4888 937);
DISPLAY 0.787234 (-4888 937);
PAINT MONO (-4888 937);
FORCEPROP 2 LAST CDS_LIB pure_quanta
J 0
(-4950 925);
DISPLAY INVISIBLE (-4950 925);
FORCEPROP 1 LAST PATH I75
J 0
(-5000 1075);
DISPLAY 0.978723 (-5000 1075);
PAINT WHITE (-5000 1075);
DISPLAY INVISIBLE (-5000 1075);
FORCEPROP 1 LAST PACK_TYPE 0402LF
J 0
(-5100 1100);
DISPLAY 0.787234 (-5100 1100);
DISPLAY INVISIBLE (-5100 1100);
FORCEPROP 1 LAST WATTAGE 1/16W
J 2
(-4525 1100);
DISPLAY 0.787234 (-4525 1100);
DISPLAY INVISIBLE (-4525 1100);
FORCEPROP 0 LAST CDS_LOCATION R2342
J 0
(-4625 975);
DISPLAY 1.021277 (-4625 975);
DISPLAY INVISIBLE (-4625 975);
FORCEPROP 0 LAST $SEC 1
J 0
(-4625 975);
DISPLAY 0.680851 (-4625 975);
PAINT MONO (-4625 975);
DISPLAY INVISIBLE (-4625 975);
FORCEPROP 0 LAST CDS_SEC 1
J 0
(-4625 975);
DISPLAY 1.021277 (-4625 975);
DISPLAY INVISIBLE (-4625 975);
FORCEADD Q_RES..1
(1150 2750);
FORCEPROP 1 LAST PART_NUMBER CS31002FB08
J 0
(1000 2850);
DISPLAY 0.787234 (1000 2850);
DISPLAY INVISIBLE (1000 2850);
FORCEPROP 1 LAST MATERIAL CHIP
J 0
(1500 2750);
DISPLAY 0.638298 (1500 2750);
FORCEPROP 1 LAST VALUE 10K
J 2
(1375 2750);
DISPLAY 0.638298 (1375 2750);
FORCEPROP 1 LAST TOLERANCE 1%
J 0
(1400 2750);
DISPLAY 0.638298 (1400 2750);
FORCEPROP 1 LAST $LOCATION R1259
J 0
(900 2750);
DISPLAY 0.787234 (900 2750);
FORCEPROP 1 LASTPIN (1050 2750) $PN 1
J 0
(1062 2762);
DISPLAY 0.787234 (1062 2762);
FORCEPROP 1 LASTPIN (1250 2750) $PN 2
J 0
(1212 2762);
DISPLAY 0.787234 (1212 2762);
FORCEPROP 1 LAST WATTAGE 1/16W
J 2
(1575 2925);
DISPLAY 0.787234 (1575 2925);
DISPLAY INVISIBLE (1575 2925);
FORCEPROP 1 LAST PACK_TYPE 0402LF
J 0
(1000 2925);
DISPLAY 0.787234 (1000 2925);
DISPLAY INVISIBLE (1000 2925);
FORCEPROP 2 LAST CDS_LIB pure_quanta
J 0
(1150 2750);
PAINT MONO (1150 2750);
DISPLAY INVISIBLE (1150 2750);
FORCEPROP 1 LAST PATH I8
J 0
(1100 2900);
DISPLAY 0.978723 (1100 2900);
PAINT WHITE (1100 2900);
DISPLAY INVISIBLE (1100 2900);
FORCEPROP 2 LAST CDS_LOCATION R1259
J 0
(1100 2950);
DISPLAY 1.021277 (1100 2950);
DISPLAY INVISIBLE (1100 2950);
FORCEPROP 2 LAST $SEC 1
J 0
(1100 2950);
DISPLAY 0.680851 (1100 2950);
PAINT MONO (1100 2950);
DISPLAY INVISIBLE (1100 2950);
FORCEPROP 2 LAST CDS_SEC 1
J 0
(1100 2950);
DISPLAY 1.021277 (1100 2950);
DISPLAY INVISIBLE (1100 2950);
FORCEADD OFFPAGE..2
(2475 2750);
FORCEPROP 2 LAST $XR0 183 
J 0
(2664 2750);
DISPLAY 0.638298 (2664 2750);
PAINT MONO (2664 2750);
FORCEPROP 1 LAST COMMENT_BODY TRUE
J 0
(2430 2655);
DISPLAY 0.872340 (2430 2655);
PAINT GREEN (2430 2655);
DISPLAY INVISIBLE (2430 2655);
FORCEPROP 1 LAST OFFPAGE TRUE
J 0
(2800 2625);
DISPLAY 0.872340 (2800 2625);
PAINT GREEN (2800 2625);
DISPLAY INVISIBLE (2800 2625);
FORCEPROP 2 LAST CDS_LIB standard
J 0
(2475 2750);
DISPLAY INVISIBLE (2475 2750);
FORCEPROP 2 LAST PATH I9
J 0
(2675 2800);
DISPLAY 1.021277 (2675 2800);
DISPLAY INVISIBLE (2675 2800);
FORCEADD DNS..2
(1225 1300);
PAINT RED (1225 1300);
FORCEPROP 1 LAST COMMENT_BODY TRUE
R 1
J 0
(1300 1075);
DISPLAY 0.872340 (1300 1075);
PAINT GREEN (1300 1075);
DISPLAY INVISIBLE (1300 1075);
FORCEPROP 2 LAST CDS_LIB mstr_misc
J 0
(1225 1300);
PAINT MONO (1225 1300);
DISPLAY INVISIBLE (1225 1300);
FORCEADD DNS..2
(1225 1050);
PAINT RED (1225 1050);
FORCEPROP 2 LAST CDS_LIB mstr_misc
J 0
(1225 1050);
PAINT MONO (1225 1050);
DISPLAY INVISIBLE (1225 1050);
FORCEPROP 1 LAST COMMENT_BODY TRUE
R 1
J 0
(1300 825);
DISPLAY 0.872340 (1300 825);
PAINT GREEN (1300 825);
DISPLAY INVISIBLE (1300 825);
FORCEADD DNS..2
(1225 1175);
PAINT RED (1225 1175);
FORCEPROP 2 LAST CDS_LIB mstr_misc
J 0
(1225 1175);
PAINT MONO (1225 1175);
DISPLAY INVISIBLE (1225 1175);
FORCEPROP 1 LAST COMMENT_BODY TRUE
R 1
J 0
(1300 950);
DISPLAY 0.872340 (1300 950);
PAINT GREEN (1300 950);
DISPLAY INVISIBLE (1300 950);
FORCEADD DNS..2
(-4900 -850);
PAINT RED (-4900 -850);
FORCEPROP 1 LAST COMMENT_BODY TRUE
R 1
J 0
(-4825 -1075);
DISPLAY 0.872340 (-4825 -1075);
PAINT GREEN (-4825 -1075);
DISPLAY INVISIBLE (-4825 -1075);
FORCEPROP 2 LAST CDS_LIB mstr_misc
J 0
(-4900 -850);
PAINT MONO (-4900 -850);
DISPLAY INVISIBLE (-4900 -850);
FORCEADD QUANTA_TITLE_BLOCK_C..1
(3475 -2225);
FORCEPROP 0 LAST CDS_CON_LAST_MODIFIED Fri Aug 25 14:03:20 2023
J 0
(1590 -2210);
PAINT MONO (1590 -2210);
DISPLAY INVISIBLE (1590 -2210);
FORCEPROP 2 LAST CUSTOM_TXT_CDS <XR_PAGE_TITLE>
J 0
(-4415 3025);
DISPLAY 0.638298 (-4415 3025);
PAINT PINK (-4415 3025);
DISPLAY INVISIBLE (-4415 3025);
FORCEPROP 2 LAST CUSTOM_TXT_CDS <NAME_2>
J 0
(300 -2175);
FORCEPROP 2 LAST CUSTOM_TXT_CDS <NAME_1>
J 0
(300 -2050);
FORCEPROP 2 LAST CUSTOM_TXT_CDS <Q_NUMBER>
J 0
(2072 -2122);
DISPLAY 1.212766 (2072 -2122);
FORCEPROP 2 LAST CUSTOM_TXT_CDS <Q_PROJ>
J 0
(1093 -2123);
DISPLAY 1.212766 (1093 -2123);
FORCEPROP 2 LAST CUSTOM_TXT_CDS <Q_REV>
J 0
(3291 -2122);
DISPLAY 1.212766 (3291 -2122);
FORCEPROP 2 LAST CUSTOM_TXT_CDS <CON_PAGE_NUM> OF <CON_TOTAL_PAGES>
J 0
(3029 -2207);
DISPLAY 0.978723 (3029 -2207);
FORCEPROP 2 LAST CUSTOM_TXT_CDS <CON_LAST_MODIFIED>
J 0
(1590 -2210);
DISPLAY 0.978723 (1590 -2210);
FORCEPROP 1 LAST Q_TITLE PCH TERMINATION(1/2)
J 0
(-5791 -2199);
DISPLAY 2.446809 (-5791 -2199);
PAINT GREEN (-5791 -2199);
FORCEPROP 1 LAST Q_DEPT 
J 1
(-288 -2176);
DISPLAY 1.957447 (-288 -2176);
PAINT GREEN (-288 -2176);
FORCEPROP 2 LAST CDS_XR_PAGE_TITLE CR-204 : @S9S_MB_2U_LIB.S9S_MB_2U(SCH_1):PAGE204
J 0
(-4415 3025);
DISPLAY 0.638298 (-4415 3025);
PAINT PINK (-4415 3025);
DISPLAY INVISIBLE (-4415 3025);
FORCEPROP 2 LAST PAGE_BORDER TRUE
J 0
(-4415 3025);
DISPLAY 0.638298 (-4415 3025);
PAINT PINK (-4415 3025);
DISPLAY INVISIBLE (-4415 3025);
FORCEPROP 1 LAST COMMENT_BODY TRUE
J 0
(3487 -2238);
DISPLAY 0.978723 (3487 -2238);
PAINT GREEN (3487 -2238);
DISPLAY INVISIBLE (3487 -2238);
FORCEPROP 1 LAST CDS_LMAN_SYM_OUTLINE -9475,6775,100,-125
J 0
(3475 -2225);
DISPLAY 0.468085 (3475 -2225);
PAINT GREEN (3475 -2225);
DISPLAY INVISIBLE (3475 -2225);
FORCEPROP 2 LAST CDS_LIB pure_quanta
J 0
(3475 -2225);
PAINT MONO (3475 -2225);
DISPLAY INVISIBLE (3475 -2225);
WIRE 16 -1 (-5300 -600)(-5300 -850);
WIRE 16 -1 (-2200 1550)(-2200 1300);
WIRE 16 -1 (-5300 1550)(-5300 1300);
WIRE 16 -1 (825 -625)(825 -850);
WIRE 16 -1 (-2200 3025)(-2200 3400);
WIRE 16 -1 (-2200 2900)(-2200 3025);
WIRE 16 -1 (-1950 3025)(-2200 3025);
WIRE 16 -1 (-5300 3375)(-5300 3125);
WIRE 16 -1 (800 3325)(800 3150);
WIRE 16 -1 (825 1550)(825 1300);
WIRE 16 -1 (-5050 2875)(-5300 2875);
WIRE 16 -1 (-5300 2875)(-5300 3000);
WIRE 16 -1 (-5050 3000)(-5300 3000);
WIRE 16 -1 (-5300 3125)(-5300 3000);
WIRE 16 -1 (-5300 3125)(-5050 3125);
WIRE 16 -1 (-3550 2875)(-4850 2875);
FORCEPROP 2 LAST SIG_NAME ESPI_ALERT1_N_LPC_RCIN_N
J 0
(-4375 2885);
DISPLAY 0.553191 (-4375 2885);
PAINT WHITE (-4375 2885);
WIRE 16 -1 (-3550 3125)(-4850 3125);
FORCEPROP 2 LAST SIG_NAME IRQ_LPC_PIRQA_N_ESPI_ALERT0_N
J 0
(-4375 3135);
DISPLAY 0.553191 (-4375 3135);
PAINT WHITE (-4375 3135);
WIRE 16 -1 (800 3150)(1050 3150);
WIRE 16 -1 (800 3150)(800 3025);
WIRE 16 -1 (1050 3025)(800 3025);
WIRE 16 -1 (800 2875)(800 3025);
WIRE 16 -1 (1050 2875)(800 2875);
WIRE 16 -1 (800 2750)(800 2875);
WIRE 16 -1 (1050 2750)(800 2750);
WIRE 16 -1 (800 2625)(800 2750);
WIRE 16 -1 (1050 2625)(800 2625);
WIRE 16 -1 (2425 3150)(1250 3150);
FORCEPROP 2 LAST SIG_NAME IRQ_PCH_SCI_WHEA_N
J 0
(1800 3160);
DISPLAY 0.553191 (1800 3160);
PAINT WHITE (1800 3160);
WIRE 16 -1 (-3550 3000)(-4850 3000);
FORCEPROP 2 LAST SIG_NAME IRQ_LPC_SERIRQ_ESPI_CS1_N
J 0
(-4375 3010);
DISPLAY 0.553191 (-4375 3010);
PAINT WHITE (-4375 3010);
WIRE 16 -1 (825 1300)(1100 1300);
WIRE 16 -1 (825 1300)(825 1175);
WIRE 16 -1 (1100 1175)(825 1175);
WIRE 16 -1 (825 1050)(825 1175);
WIRE 16 -1 (1100 1050)(825 1050);
WIRE 16 -1 (2425 1175)(1300 1175);
FORCEPROP 2 LAST SIG_NAME H_CPU_ERR1_PCH_R_N
J 0
(1850 1185);
DISPLAY 0.553191 (1850 1185);
PAINT WHITE (1850 1185);
WIRE 16 -1 (2425 1300)(1300 1300);
FORCEPROP 2 LAST SIG_NAME H_CPU_ERR0_PCH_R_N
J 0
(1850 1310);
DISPLAY 0.553191 (1850 1310);
PAINT WHITE (1850 1310);
WIRE 16 -1 (2425 1050)(1300 1050);
FORCEPROP 0 LAST CDS_PHYS_NET_NAME H_CPU_ERR0_PCH_N
J 0
(1850 1086);
PAINT MONO (1850 1086);
DISPLAY INVISIBLE (1850 1086);
FORCEPROP 2 LAST SIG_NAME H_CPU_ERR2_PCH_R_N
J 0
(1850 1060);
DISPLAY 0.553191 (1850 1060);
PAINT WHITE (1850 1060);
WIRE 16 -1 (-5050 925)(-5300 925);
WIRE 16 -1 (-5300 1050)(-5300 925);
WIRE 16 -1 (-5050 1050)(-5300 1050);
WIRE 16 -1 (-5300 1175)(-5300 1050);
WIRE 16 -1 (-5050 1175)(-5300 1175);
WIRE 16 -1 (-5300 1300)(-5300 1175);
WIRE 16 -1 (-5300 1300)(-5050 1300);
WIRE 16 -1 (-3550 925)(-4850 925);
FORCEPROP 2 LAST SIG_NAME FM_DEBUG_PORT_PRSNT_R_N
J 0
(-4375 935);
DISPLAY 0.553191 (-4375 935);
PAINT WHITE (-4375 935);
WIRE 16 -1 (2425 2625)(1250 2625);
FORCEPROP 2 LAST SIG_NAME FM_PCHHOT_N
J 0
(1800 2635);
DISPLAY 0.553191 (1800 2635);
PAINT WHITE (1800 2635);
WIRE 16 -1 (-5300 -850)(-5025 -850);
WIRE 16 -1 (-3700 -850)(-4825 -850);
FORCEPROP 2 LAST SIG_NAME IRQ_TPM_SPI_N
J 0
(-4275 -840);
DISPLAY 0.553191 (-4275 -840);
PAINT WHITE (-4275 -840);
WIRE 16 -1 (-2200 1300)(-1950 1300);
WIRE 16 -1 (-450 1300)(-1750 1300);
FORCEPROP 2 LAST SIG_NAME PU_PCH_PMCALERT_N
J 0
(-1275 1310);
DISPLAY 0.553191 (-1275 1310);
PAINT WHITE (-1275 1310);
WIRE 16 -1 (-3550 1050)(-4850 1050);
FORCEPROP 2 LAST SIG_NAME FM_ME_AUTHN_FAIL
J 0
(-4375 1060);
DISPLAY 0.553191 (-4375 1060);
PAINT WHITE (-4375 1060);
WIRE 16 -1 (-3550 1175)(-4850 1175);
FORCEPROP 2 LAST SIG_NAME FM_ME_BT_DONE
J 0
(-4375 1185);
DISPLAY 0.553191 (-4375 1185);
PAINT WHITE (-4375 1185);
WIRE 16 -1 (-3550 1300)(-4850 1300);
FORCEPROP 2 LAST SIG_NAME FM_PS_PWROK_DLY_R_SEL
J 0
(-4375 1310);
DISPLAY 0.553191 (-4375 1310);
PAINT WHITE (-4375 1310);
WIRE 16 -1 (1100 -975)(825 -975);
WIRE 16 -1 (825 -850)(825 -975);
WIRE 16 -1 (825 -850)(1100 -850);
WIRE 16 -1 (2600 -975)(1300 -975);
FORCEPROP 2 LAST SIG_NAME IRQ_PCH_CPU_NMI_EVENT_R_N
J 0
(1850 -965);
DISPLAY 0.553191 (1850 -965);
PAINT WHITE (1850 -965);
WIRE 16 -1 (2600 -850)(1300 -850);
FORCEPROP 2 LAST SIG_NAME IRQ_SMI_ACTIVE_N
J 0
(1850 -840);
DISPLAY 0.553191 (1850 -840);
PAINT WHITE (1850 -840);
WIRE 16 -1 (-1950 2900)(-2200 2900);
WIRE 16 -1 (-550 2900)(-1750 2900);
FORCEPROP 2 LAST SIG_NAME FM_THROTTLE_N
J 0
(-1200 2910);
DISPLAY 0.553191 (-1200 2910);
PAINT WHITE (-1200 2910);
WIRE 16 -1 (-550 3025)(-1750 3025);
FORCEPROP 2 LAST SIG_NAME FM_BIOS_POST_CMPLT_N
J 0
(-1200 3035);
DISPLAY 0.553191 (-1200 3035);
PAINT WHITE (-1200 3035);
WIRE 16 -1 (2425 2750)(1250 2750);
FORCEPROP 2 LAST SIG_NAME PU_LPC_PME_N
J 0
(1800 2760);
DISPLAY 0.553191 (1800 2760);
PAINT WHITE (1800 2760);
WIRE 16 -1 (2425 2875)(1250 2875);
FORCEPROP 2 LAST SIG_NAME FM_PCH_GLB_RST_WARN_N
J 0
(1800 2885);
DISPLAY 0.553191 (1800 2885);
PAINT WHITE (1800 2885);
WIRE 16 -1 (2425 3025)(1250 3025);
FORCEPROP 2 LAST SIG_NAME PU_PCH_VRALERT_N
J 0
(1800 3035);
DISPLAY 0.553191 (1800 3035);
PAINT WHITE (1800 3035);
WIRE 16 273 (-5650 2275)(3300 2275);
WIRE 16 273 (-5700 300)(3250 300);
DOT 1 (-2200 3025);
DOT 1 (-5300 1300);
DOT 1 (800 3025);
DOT 1 (800 3150);
DOT 1 (825 -850);
DOT 1 (800 2875);
DOT 1 (825 1300);
DOT 1 (-5300 1175);
DOT 1 (825 1175);
DOT 1 (800 2750);
DOT 1 (-5300 3000);
DOT 1 (-5300 3125);
DOT 1 (-5300 1050);
FORCENOTE
GPIO BANK D
(1100 3850) 0;
DISPLAY LEFT (1100 3850);
DISPLAY 2.000000 (1100 3850);
PAINT SKYBLUE (1100 3850);
FORCENOTE
GPIO BANK J
(1125 2025) 0;
DISPLAY LEFT (1125 2025);
DISPLAY 2.000000 (1125 2025);
PAINT SKYBLUE (1125 2025);
FORCENOTE
GPIO BANK C
(-1900 3875) 0;
DISPLAY LEFT (-1900 3875);
DISPLAY 2.000000 (-1900 3875);
PAINT SKYBLUE (-1900 3875);
FORCENOTE
GPIO BANK S
(1125 -125) 0;
DISPLAY LEFT (1125 -125);
DISPLAY 2.000000 (1125 -125);
PAINT SKYBLUE (1125 -125);
FORCENOTE
GPIO BANK A
(-5000 3850) 0;
DISPLAY LEFT (-5000 3850);
DISPLAY 2.000000 (-5000 3850);
PAINT SKYBLUE (-5000 3850);
FORCENOTE
GPIO BANK H
(-1900 2025) 0;
DISPLAY LEFT (-1900 2025);
DISPLAY 2.000000 (-1900 2025);
PAINT SKYBLUE (-1900 2025);
FORCENOTE
GPIO BANK E
(-5000 2025) 0;
DISPLAY LEFT (-5000 2025);
DISPLAY 2.000000 (-5000 2025);
PAINT SKYBLUE (-5000 2025);
FORCENOTE
GPIO BANK I
(-5000 -125) 0;
DISPLAY LEFT (-5000 -125);
DISPLAY 2.000000 (-5000 -125);
PAINT SKYBLUE (-5000 -125);
QUIT
